# T6G (Grand Teton) — schematic netlist excerpt (pin names and nets, part order shuffled) for the footprints in the layout excerpt that follows; sources: Cadence DE-HDL packaged netlist, KiCad conversion of 04192023_DAF0TMB3IC0_F0TG_MB_C_brd_V02_OCP.brd

PC83  Q_CAP  22UF 4V 20% X6S  pkg C0805  page 226 : A = PVDD18_S5_P1 ; B = GND
R416  Q_RES  2.2K 5% CHIP  pkg 0402LF  page 27 : A = CPU0_XTRIG_L7 ; B = PVDD18_S5_P0
PC95  Q_CAP  0.1UF 25V 10% X7R  pkg 0402  page 224 : A = PVDD11_S3_P1_VCC ; B = GND

(kicad_pcb
	(version 20260206)
	(generator "pcbnew")
	(generator_version "10.0")
	(general
		(thickness 1.6)
		(legacy_teardrops no)
	)
	(paper "A4")
	(title_block
		(title "04192023_DAF0TMB3IC0_F0TG_MB_C_brd_V02_OCP.brd")
		(comment 1 "Grand Teton / footprints 3539-3541 of 8354")
	)
	(layers
		(0 "F.Cu" signal "TOP")
		(4 "In1.Cu" signal "GND")
		(6 "In2.Cu" signal "IN1")
		(8 "In3.Cu" signal "GND1")
		(10 "In4.Cu" signal "IN2")
		(12 "In5.Cu" signal "GND2")
		(14 "In6.Cu" signal "IN3")
		(16 "In7.Cu" signal "GND3")
		(18 "In8.Cu" signal "VCC")
		(20 "In9.Cu" signal "VCC1")
		(22 "In10.Cu" signal "GND4")
		(24 "In11.Cu" signal "IN4")
		(26 "In12.Cu" signal "GND5")
		(28 "In13.Cu" signal "IN5")
		(30 "In14.Cu" signal "GND6")
		(32 "In15.Cu" signal "IN6")
		(34 "In16.Cu" signal "GND7")
		(2 "B.Cu" signal "BOTTOM")
		(9 "F.Adhes" user "F.Adhesive")
		(11 "B.Adhes" user "B.Adhesive")
		(13 "F.Paste" user "Package Geometry/Pastemask Top")
		(15 "B.Paste" user "Package Geometry/Pastemask Bottom")
		(5 "F.SilkS" user "Ref Des/Silkscreen Top")
		(7 "B.SilkS" user "Ref Des/Silkscreen Bottom")
		(1 "F.Mask" user "Board Geometry/Soldermask Top")
		(3 "B.Mask" user "Board Geometry/Soldermask Bottom")
		(17 "Dwgs.User" user "User.Drawings")
		(19 "Cmts.User" user "User.Comments")
		(21 "Eco1.User" user "User.Eco1")
		(23 "Eco2.User" user "User.Eco2")
		(25 "Edge.Cuts" user "Board Geometry/Outline")
		(27 "Margin" user)
		(31 "F.CrtYd" user "Package Geometry/Place Bound Top")
		(29 "B.CrtYd" user "Package Geometry/Place Bound Bottom")
		(35 "F.Fab" user "Ref Des/Assembly Top")
		(33 "B.Fab" user "Ref Des/Assembly Bottom")
	)
	(footprint ""
		(layer "F.Cu")
		(at 166.548308 -352.278442 90)
		(property "Reference" "PC95"
			(at 0 0 90)
			(layer "F.SilkS")
			(hide yes)
			(effects
				(font
					(size 1.27 1.27)
				)
			)
		)
		(property "Value" ""
			(at 0 0 90)
			(layer "F.Fab")
			(effects
				(font
					(size 1.27 1.27)
				)
			)
		)
		(duplicate_pad_numbers_are_jumpers no)
		(fp_line
			(start 0.7874 -0.4064)
			(end 0.7874 0.4064)
			(stroke
				(width 0.1524)
				(type default)
			)
			(layer "F.SilkS")
		)
		(fp_line
			(start -0.7874 -0.4064)
			(end 0.7874 -0.4064)
			(stroke
				(width 0.1524)
				(type default)
			)
			(layer "F.SilkS")
		)
		(fp_line
			(start 0.7874 0.4064)
			(end -0.7874 0.4064)
			(stroke
				(width 0.1524)
				(type default)
			)
			(layer "F.SilkS")
		)
		(fp_line
			(start -0.7874 0.4064)
			(end -0.7874 -0.4064)
			(stroke
				(width 0.1524)
				(type default)
			)
			(layer "F.SilkS")
		)
		(fp_line
			(start -0.12065 -0.305054)
			(end -0.12065 -0.2794)
			(stroke
				(width 0.1)
				(type default)
			)
			(layer "F.Fab")
		)
		(fp_line
			(start -0.67945 -0.305054)
			(end -0.12065 -0.305054)
			(stroke
				(width 0.1)
				(type default)
			)
			(layer "F.Fab")
		)
		(fp_line
			(start 0.67945 -0.3048)
			(end 0.67945 0.3048)
			(stroke
				(width 0.1)
				(type default)
			)
			(layer "F.Fab")
		)
		(fp_line
			(start 0.12065 -0.3048)
			(end 0.67945 -0.3048)
			(stroke
				(width 0.1)
				(type default)
			)
			(layer "F.Fab")
		)
		(fp_line
			(start 0.12065 -0.2794)
			(end 0.12065 -0.3048)
			(stroke
				(width 0.1)
				(type default)
			)
			(layer "F.Fab")
		)
		(fp_line
			(start -0.12065 -0.2794)
			(end 0.12065 -0.2794)
			(stroke
				(width 0.1)
				(type default)
			)
			(layer "F.Fab")
		)
		(fp_line
			(start 0.120396 0.2794)
			(end -0.12065 0.2794)
			(stroke
				(width 0.1)
				(type default)
			)
			(layer "F.Fab")
		)
		(fp_line
			(start -0.12065 0.2794)
			(end -0.12065 0.3048)
			(stroke
				(width 0.1)
				(type default)
			)
			(layer "F.Fab")
		)
		(fp_line
			(start 0.67945 0.3048)
			(end 0.120396 0.3048)
			(stroke
				(width 0.1)
				(type default)
			)
			(layer "F.Fab")
		)
		(fp_line
			(start 0.120396 0.3048)
			(end 0.120396 0.2794)
			(stroke
				(width 0.1)
				(type default)
			)
			(layer "F.Fab")
		)
		(fp_line
			(start -0.12065 0.3048)
			(end -0.67945 0.3048)
			(stroke
				(width 0.1)
				(type default)
			)
			(layer "F.Fab")
		)
		(fp_line
			(start -0.67945 0.3048)
			(end -0.67945 -0.305054)
			(stroke
				(width 0.1)
				(type default)
			)
			(layer "F.Fab")
		)
		(pad "1" smd circle
			(at -0.40005 0 90)
			(size 0 0)
			(layers "F.Cu" "F.Mask" "F.Paste")
			(net "PVDD11_S3_P1_VCC")
		)
		(pad "2" smd circle
			(at 0.40005 0 90)
			(size 0 0)
			(layers "F.Cu" "F.Mask" "F.Paste")
			(net "GND")
		)
	)
	(footprint ""
		(layer "F.Cu")
		(at 330.371958 -193.163952 -90)
		(property "Reference" "R416"
			(at 0 0 270)
			(layer "F.SilkS")
			(hide yes)
			(effects
				(font
					(size 1.27 1.27)
				)
			)
		)
		(property "Value" ""
			(at 0 0 270)
			(layer "F.Fab")
			(effects
				(font
					(size 1.27 1.27)
				)
			)
		)
		(duplicate_pad_numbers_are_jumpers no)
		(fp_line
			(start -0.7874 0.4064)
			(end -0.7874 -0.4064)
			(stroke
				(width 0.1524)
				(type default)
			)
			(layer "F.SilkS")
		)
		(fp_line
			(start 0.7874 0.4064)
			(end -0.7874 0.4064)
			(stroke
				(width 0.1524)
				(type default)
			)
			(layer "F.SilkS")
		)
		(fp_line
			(start -0.7874 -0.4064)
			(end 0.7874 -0.4064)
			(stroke
				(width 0.1524)
				(type default)
			)
			(layer "F.SilkS")
		)
		(fp_line
			(start 0.7874 -0.4064)
			(end 0.7874 0.4064)
			(stroke
				(width 0.1524)
				(type default)
			)
			(layer "F.SilkS")
		)
		(fp_line
			(start -0.67945 0.3048)
			(end -0.67945 -0.305054)
			(stroke
				(width 0.1)
				(type default)
			)
			(layer "F.Fab")
		)
		(fp_line
			(start -0.12065 0.3048)
			(end -0.67945 0.3048)
			(stroke
				(width 0.1)
				(type default)
			)
			(layer "F.Fab")
		)
		(fp_line
			(start 0.120396 0.3048)
			(end 0.120396 0.2794)
			(stroke
				(width 0.1)
				(type default)
			)
			(layer "F.Fab")
		)
		(fp_line
			(start 0.67945 0.3048)
			(end 0.120396 0.3048)
			(stroke
				(width 0.1)
				(type default)
			)
			(layer "F.Fab")
		)
		(fp_line
			(start -0.12065 0.2794)
			(end -0.12065 0.3048)
			(stroke
				(width 0.1)
				(type default)
			)
			(layer "F.Fab")
		)
		(fp_line
			(start 0.120396 0.2794)
			(end -0.12065 0.2794)
			(stroke
				(width 0.1)
				(type default)
			)
			(layer "F.Fab")
		)
		(fp_line
			(start -0.12065 -0.2794)
			(end 0.12065 -0.2794)
			(stroke
				(width 0.1)
				(type default)
			)
			(layer "F.Fab")
		)
		(fp_line
			(start 0.12065 -0.2794)
			(end 0.12065 -0.3048)
			(stroke
				(width 0.1)
				(type default)
			)
			(layer "F.Fab")
		)
		(fp_line
			(start 0.12065 -0.3048)
			(end 0.67945 -0.3048)
			(stroke
				(width 0.1)
				(type default)
			)
			(layer "F.Fab")
		)
		(fp_line
			(start 0.67945 -0.3048)
			(end 0.67945 0.3048)
			(stroke
				(width 0.1)
				(type default)
			)
			(layer "F.Fab")
		)
		(fp_line
			(start -0.67945 -0.305054)
			(end -0.12065 -0.305054)
			(stroke
				(width 0.1)
				(type default)
			)
			(layer "F.Fab")
		)
		(fp_line
			(start -0.12065 -0.305054)
			(end -0.12065 -0.2794)
			(stroke
				(width 0.1)
				(type default)
			)
			(layer "F.Fab")
		)
		(pad "1" smd circle
			(at -0.40005 0 270)
			(size 0 0)
			(layers "F.Cu" "F.Mask" "F.Paste")
			(net "CPU0_XTRIG_L7")
		)
		(pad "2" smd circle
			(at 0.40005 0 270)
			(size 0 0)
			(layers "F.Cu" "F.Mask" "F.Paste")
			(net "PVDD18_S5_P0")
		)
	)
	(footprint ""
		(layer "F.Cu")
		(at 52.143406 -152.20823 180)
		(property "Reference" "PC83"
			(at 0 0 180)
			(layer "F.SilkS")
			(hide yes)
			(effects
				(font
					(size 1.27 1.27)
				)
			)
		)
		(property "Value" ""
			(at 0 0 180)
			(layer "F.Fab")
			(effects
				(font
					(size 1.27 1.27)
				)
			)
		)
		(duplicate_pad_numbers_are_jumpers no)
		(fp_line
			(start 1.524 0.762)
			(end -1.524 0.762)
			(stroke
				(width 0.1524)
				(type default)
			)
			(layer "F.SilkS")
		)
		(fp_line
			(start 1.524 -0.762)
			(end 1.524 0.762)
			(stroke
				(width 0.1524)
				(type default)
			)
			(layer "F.SilkS")
		)
		(fp_line
			(start -1.524 0.762)
			(end -1.524 -0.762)
			(stroke
				(width 0.1524)
				(type default)
			)
			(layer "F.SilkS")
		)
		(fp_line
			(start -1.524 -0.762)
			(end 1.524 -0.762)
			(stroke
				(width 0.1524)
				(type default)
			)
			(layer "F.SilkS")
		)
		(fp_line
			(start 1.1049 0.724916)
			(end 1.1049 -0.724916)
			(stroke
				(width 0.1)
				(type default)
			)
			(layer "F.Fab")
		)
		(fp_line
			(start 1.1049 -0.724916)
			(end -1.1049 -0.724916)
			(stroke
				(width 0.1)
				(type default)
			)
			(layer "F.Fab")
		)
		(fp_line
			(start -1.1049 0.724916)
			(end 1.1049 0.724916)
			(stroke
				(width 0.1)
				(type default)
			)
			(layer "F.Fab")
		)
		(fp_line
			(start -1.1049 -0.724916)
			(end -1.1049 0.724916)
			(stroke
				(width 0.1)
				(type default)
			)
			(layer "F.Fab")
		)
		(pad "1" smd rect
			(at -0.889 0)
			(size 1.016 1.27)
			(layers "F.Cu" "F.Mask" "F.Paste")
			(net "PVDD18_S5_P1")
		)
		(pad "2" smd rect
			(at 0.889 0)
			(size 1.016 1.27)
			(layers "F.Cu" "F.Mask" "F.Paste")
			(net "GND")
		)
	)
)
